(kicad_pcb
	(version 20260206)
	(generator "pcbnew")
	(generator_version "10.0")
	(general
		(thickness 1.6)
		(legacy_teardrops no)
	)
	(paper "A4")
	(title_block
		(title "v1-chassis-manager — T6M_CM_d_v01_1031_1645.brd")
		(comment 1 "Open CloudServer (Microsoft) / footprints 1973-1982 of 2512")
	)
	(layers
		(0 "F.Cu" signal "TOP")
		(4 "In1.Cu" signal "GND1")
		(6 "In2.Cu" signal "IN1")
		(8 "In3.Cu" signal "VCC1")
		(10 "In4.Cu" signal "VCC2")
		(12 "In5.Cu" signal "GND2")
		(14 "In6.Cu" signal "IN2")
		(16 "In7.Cu" signal "IN3")
		(18 "In8.Cu" signal "GND3")
		(2 "B.Cu" signal "BOTTOM")
		(9 "F.Adhes" user "F.Adhesive")
		(11 "B.Adhes" user "B.Adhesive")
		(13 "F.Paste" user "Package Geometry/Pastemask Top")
		(15 "B.Paste" user "Package Geometry/Pastemask Bottom")
		(5 "F.SilkS" user "Ref Des/Silkscreen Top")
		(7 "B.SilkS" user "Ref Des/Silkscreen Bottom")
		(1 "F.Mask" user "Board Geometry/Soldermask Top")
		(3 "B.Mask" user "Board Geometry/Soldermask Bottom")
		(17 "Dwgs.User" user "User.Drawings")
		(19 "Cmts.User" user "User.Comments")
		(21 "Eco1.User" user "User.Eco1")
		(23 "Eco2.User" user "User.Eco2")
		(25 "Edge.Cuts" user "Board Geometry/Outline")
		(27 "Margin" user)
		(31 "F.CrtYd" user "Package Geometry/Place Bound Top")
		(29 "B.CrtYd" user "Package Geometry/Place Bound Bottom")
		(35 "F.Fab" user "Ref Des/Assembly Top")
		(33 "B.Fab" user "Ref Des/Assembly Bottom")
	)
	(footprint ""
		(layer "B.Cu")
		(at 155.644596 -67.23253 -90)
		(property "Reference" "L33"
			(at -0.021082 -5.14731 270)
			(unlocked yes)
			(layer "B.SilkS")
			(effects
				(font
					(size 0.7874 0.5842)
					(thickness 0.1524)
				)
				(justify left mirror)
			)
		)
		(property "Value" ""
			(at 0 0 90)
			(layer "B.Fab")
			(effects
				(font
					(size 1.27 1.27)
				)
				(justify mirror)
			)
		)
		(duplicate_pad_numbers_are_jumpers no)
		(fp_line
			(start -0.7874 0.4064)
			(end 0.7874 0.4064)
			(stroke
				(width 0.1524)
				(type default)
			)
			(layer "B.SilkS")
		)
		(fp_line
			(start -0.0889 0.4064)
			(end -0.0889 -0.4064)
			(stroke
				(width 0.1524)
				(type default)
			)
			(layer "B.SilkS")
		)
		(fp_line
			(start 0.0889 0.4064)
			(end 0.0889 -0.4064)
			(stroke
				(width 0.1524)
				(type default)
			)
			(layer "B.SilkS")
		)
		(fp_line
			(start 0.7874 0.4064)
			(end 0.7874 -0.4064)
			(stroke
				(width 0.1524)
				(type default)
			)
			(layer "B.SilkS")
		)
		(fp_line
			(start -0.7874 -0.4064)
			(end -0.7874 0.4064)
			(stroke
				(width 0.1524)
				(type default)
			)
			(layer "B.SilkS")
		)
		(fp_line
			(start 0.7874 -0.4064)
			(end -0.7874 -0.4064)
			(stroke
				(width 0.1524)
				(type default)
			)
			(layer "B.SilkS")
		)
		(fp_poly
			(pts
				(xy 0.5334 0.254) (xy 0.635 0.254) (xy 0.635 0.2286) (xy 0.635 -0.254) (xy 0.5334 -0.254) (xy 0.5334 -0.2794)
				(xy -0.5334 -0.2794) (xy -0.5334 -0.254) (xy -0.635 -0.254) (xy -0.635 0.254) (xy -0.5334 0.254)
				(xy -0.5334 0.2794) (xy 0.508 0.2794) (xy 0.5334 0.2794)
			)
			(stroke
				(width 0)
				(type default)
			)
			(fill no)
			(layer "B.CrtYd")
		)
		(pad "1" smd rect
			(at -0.40005 0 90)
			(size 0.4572 0.508)
			(layers "B.Cu" "B.Mask" "B.Paste")
			(net "P1V8_NODE1")
		)
		(pad "2" smd rect
			(at 0.40005 0 90)
			(size 0.4572 0.508)
			(layers "B.Cu" "B.Mask" "B.Paste")
			(net "P1V8_SATA_VAA1_NODE1")
		)
	)
	(footprint ""
		(layer "B.Cu")
		(at 23.847298 -110.729522)
		(property "Reference" "C53"
			(at -2.920492 0.178054 0)
			(unlocked yes)
			(layer "B.SilkS")
			(effects
				(font
					(size 0.7874 0.5842)
					(thickness 0.1524)
				)
				(justify left mirror)
			)
		)
		(property "Value" ""
			(at 0 0 0)
			(layer "B.Fab")
			(effects
				(font
					(size 1.27 1.27)
				)
				(justify mirror)
			)
		)
		(duplicate_pad_numbers_are_jumpers no)
		(fp_line
			(start -1.905 -0.8636)
			(end -1.905 0.8636)
			(stroke
				(width 0.1524)
				(type default)
			)
			(layer "B.SilkS")
		)
		(fp_line
			(start -1.905 0.8636)
			(end 1.905 0.8636)
			(stroke
				(width 0.1524)
				(type default)
			)
			(layer "B.SilkS")
		)
		(fp_line
			(start 0 0.8382)
			(end 0 -0.8382)
			(stroke
				(width 0.1524)
				(type default)
			)
			(layer "B.SilkS")
		)
		(fp_line
			(start 1.905 -0.8636)
			(end -1.905 -0.8636)
			(stroke
				(width 0.1524)
				(type default)
			)
			(layer "B.SilkS")
		)
		(fp_line
			(start 1.905 0.8636)
			(end 1.905 -0.8636)
			(stroke
				(width 0.1524)
				(type default)
			)
			(layer "B.SilkS")
		)
		(fp_rect
			(start 1.524 0.7366)
			(end -1.524 -0.7366)
			(stroke
				(width 0)
				(type default)
			)
			(fill no)
			(layer "B.CrtYd")
		)
		(pad "1" smd rect
			(at -0.94996 0 180)
			(size 1.1176 1.3716)
			(layers "B.Cu" "B.Mask" "B.Paste")
			(net "P1V05_NODE1")
		)
		(pad "2" smd rect
			(at 0.94996 0 180)
			(size 1.1176 1.3716)
			(layers "B.Cu" "B.Mask" "B.Paste")
			(net "GND")
		)
	)
	(footprint ""
		(layer "B.Cu")
		(at 67.111372 -80.514698 90)
		(property "Reference" "C65"
			(at -32.09925 -14.534642 270)
			(unlocked yes)
			(layer "B.SilkS")
			(effects
				(font
					(size 0.7874 0.5842)
					(thickness 0.1524)
				)
				(justify left mirror)
			)
		)
		(property "Value" ""
			(at 0 0 90)
			(layer "B.Fab")
			(effects
				(font
					(size 1.27 1.27)
				)
				(justify mirror)
			)
		)
		(duplicate_pad_numbers_are_jumpers no)
		(fp_line
			(start 0.7874 -0.4064)
			(end -0.7874 -0.4064)
			(stroke
				(width 0.1524)
				(type default)
			)
			(layer "B.SilkS")
		)
		(fp_line
			(start -0.7874 -0.4064)
			(end -0.7874 0.4064)
			(stroke
				(width 0.1524)
				(type default)
			)
			(layer "B.SilkS")
		)
		(fp_line
			(start 0 0.381)
			(end 0 -0.381)
			(stroke
				(width 0.1524)
				(type default)
			)
			(layer "B.SilkS")
		)
		(fp_line
			(start 0.7874 0.4064)
			(end 0.7874 -0.4064)
			(stroke
				(width 0.1524)
				(type default)
			)
			(layer "B.SilkS")
		)
		(fp_line
			(start -0.7874 0.4064)
			(end 0.7874 0.4064)
			(stroke
				(width 0.1524)
				(type default)
			)
			(layer "B.SilkS")
		)
		(fp_poly
			(pts
				(xy 0.5334 0.254) (xy 0.635 0.254) (xy 0.635 0.2286) (xy 0.635 -0.254) (xy 0.5334 -0.254) (xy 0.5334 -0.2794)
				(xy -0.5334 -0.2794) (xy -0.5334 -0.254) (xy -0.635 -0.254) (xy -0.635 0.254) (xy -0.5334 0.254)
				(xy -0.5334 0.2794) (xy 0.508 0.2794) (xy 0.5334 0.2794)
			)
			(stroke
				(width 0)
				(type default)
			)
			(fill no)
			(layer "B.CrtYd")
		)
		(pad "1" smd rect
			(at -0.40005 0 270)
			(size 0.4572 0.508)
			(layers "B.Cu" "B.Mask" "B.Paste")
			(net "PV_VCCP_NODE1")
		)
		(pad "2" smd rect
			(at 0.40005 0 270)
			(size 0.4572 0.508)
			(layers "B.Cu" "B.Mask" "B.Paste")
			(net "GND")
		)
	)
	(footprint ""
		(layer "B.Cu")
		(at 163.128452 -99.58959 180)
		(property "Reference" "C376"
			(at -4.541012 0.26543 0)
			(unlocked yes)
			(layer "B.SilkS")
			(effects
				(font
					(size 0.7874 0.5842)
					(thickness 0.1524)
				)
				(justify left mirror)
			)
		)
		(property "Value" ""
			(at 0 0 0)
			(layer "B.Fab")
			(effects
				(font
					(size 1.27 1.27)
				)
				(justify mirror)
			)
		)
		(duplicate_pad_numbers_are_jumpers no)
		(fp_line
			(start 0.7874 0.4064)
			(end 0.7874 -0.4064)
			(stroke
				(width 0.1524)
				(type default)
			)
			(layer "B.SilkS")
		)
		(fp_line
			(start 0.7874 -0.4064)
			(end -0.7874 -0.4064)
			(stroke
				(width 0.1524)
				(type default)
			)
			(layer "B.SilkS")
		)
		(fp_line
			(start 0 0.381)
			(end 0 -0.381)
			(stroke
				(width 0.1524)
				(type default)
			)
			(layer "B.SilkS")
		)
		(fp_line
			(start -0.7874 0.4064)
			(end 0.7874 0.4064)
			(stroke
				(width 0.1524)
				(type default)
			)
			(layer "B.SilkS")
		)
		(fp_line
			(start -0.7874 -0.4064)
			(end -0.7874 0.4064)
			(stroke
				(width 0.1524)
				(type default)
			)
			(layer "B.SilkS")
		)
		(fp_poly
			(pts
				(xy 0.5334 0.254) (xy 0.635 0.254) (xy 0.635 0.2286) (xy 0.635 -0.254) (xy 0.5334 -0.254) (xy 0.5334 -0.2794)
				(xy -0.5334 -0.2794) (xy -0.5334 -0.254) (xy -0.635 -0.254) (xy -0.635 0.254) (xy -0.5334 0.254)
				(xy -0.5334 0.2794) (xy 0.508 0.2794) (xy 0.5334 0.2794)
			)
			(stroke
				(width 0)
				(type default)
			)
			(fill no)
			(layer "B.CrtYd")
		)
		(pad "1" smd rect
			(at -0.40005 0)
			(size 0.4572 0.508)
			(layers "B.Cu" "B.Mask" "B.Paste")
			(net "GND")
		)
		(pad "2" smd rect
			(at 0.40005 0)
			(size 0.4572 0.508)
			(layers "B.Cu" "B.Mask" "B.Paste")
			(net "P1V05_NODE1")
		)
	)
	(footprint ""
		(layer "B.Cu")
		(at 135.747252 -135.87095 90)
		(property "Reference" "C861"
			(at -5.07365 0.34163 270)
			(unlocked yes)
			(layer "B.SilkS")
			(effects
				(font
					(size 0.7874 0.5842)
					(thickness 0.1524)
				)
				(justify left mirror)
			)
		)
		(property "Value" ""
			(at 0 0 90)
			(layer "B.Fab")
			(effects
				(font
					(size 1.27 1.27)
				)
				(justify mirror)
			)
		)
		(duplicate_pad_numbers_are_jumpers no)
		(fp_line
			(start 0.7874 -0.4064)
			(end -0.7874 -0.4064)
			(stroke
				(width 0.1524)
				(type default)
			)
			(layer "B.SilkS")
		)
		(fp_line
			(start -0.7874 -0.4064)
			(end -0.7874 0.4064)
			(stroke
				(width 0.1524)
				(type default)
			)
			(layer "B.SilkS")
		)
		(fp_line
			(start 0 0.381)
			(end 0 -0.381)
			(stroke
				(width 0.1524)
				(type default)
			)
			(layer "B.SilkS")
		)
		(fp_line
			(start 0.7874 0.4064)
			(end 0.7874 -0.4064)
			(stroke
				(width 0.1524)
				(type default)
			)
			(layer "B.SilkS")
		)
		(fp_line
			(start -0.7874 0.4064)
			(end 0.7874 0.4064)
			(stroke
				(width 0.1524)
				(type default)
			)
			(layer "B.SilkS")
		)
		(fp_poly
			(pts
				(xy 0.5334 0.254) (xy 0.635 0.254) (xy 0.635 0.2286) (xy 0.635 -0.254) (xy 0.5334 -0.254) (xy 0.5334 -0.2794)
				(xy -0.5334 -0.2794) (xy -0.5334 -0.254) (xy -0.635 -0.254) (xy -0.635 0.254) (xy -0.5334 0.254)
				(xy -0.5334 0.2794) (xy 0.508 0.2794) (xy 0.5334 0.2794)
			)
			(stroke
				(width 0)
				(type default)
			)
			(fill no)
			(layer "B.CrtYd")
		)
		(pad "1" smd rect
			(at -0.40005 0 270)
			(size 0.4572 0.508)
			(layers "B.Cu" "B.Mask" "B.Paste")
			(net "P1V0_NODE1")
		)
		(pad "2" smd rect
			(at 0.40005 0 270)
			(size 0.4572 0.508)
			(layers "B.Cu" "B.Mask" "B.Paste")
			(net "GND")
		)
	)
	(footprint ""
		(layer "B.Cu")
		(at 77.432154 -81.189322 90)
		(property "Reference" "C63"
			(at -33.359344 -14.106144 270)
			(unlocked yes)
			(layer "B.SilkS")
			(effects
				(font
					(size 0.7874 0.5842)
					(thickness 0.1524)
				)
				(justify left mirror)
			)
		)
		(property "Value" ""
			(at 0 0 90)
			(layer "B.Fab")
			(effects
				(font
					(size 1.27 1.27)
				)
				(justify mirror)
			)
		)
		(duplicate_pad_numbers_are_jumpers no)
		(fp_line
			(start 1.905 -0.8636)
			(end -1.905 -0.8636)
			(stroke
				(width 0.1524)
				(type default)
			)
			(layer "B.SilkS")
		)
		(fp_line
			(start -1.905 -0.8636)
			(end -1.905 0.8636)
			(stroke
				(width 0.1524)
				(type default)
			)
			(layer "B.SilkS")
		)
		(fp_line
			(start 0 0.8382)
			(end 0 -0.8382)
			(stroke
				(width 0.1524)
				(type default)
			)
			(layer "B.SilkS")
		)
		(fp_line
			(start 1.905 0.8636)
			(end 1.905 -0.8636)
			(stroke
				(width 0.1524)
				(type default)
			)
			(layer "B.SilkS")
		)
		(fp_line
			(start -1.905 0.8636)
			(end 1.905 0.8636)
			(stroke
				(width 0.1524)
				(type default)
			)
			(layer "B.SilkS")
		)
		(fp_rect
			(start 1.524 0.7366)
			(end -1.524 -0.7366)
			(stroke
				(width 0)
				(type default)
			)
			(fill no)
			(layer "B.CrtYd")
		)
		(pad "1" smd rect
			(at -0.94996 0 270)
			(size 1.1176 1.3716)
			(layers "B.Cu" "B.Mask" "B.Paste")
			(net "PV_VCCP_NODE1")
		)
		(pad "2" smd rect
			(at 0.94996 0 270)
			(size 1.1176 1.3716)
			(layers "B.Cu" "B.Mask" "B.Paste")
			(net "GND")
		)
	)
	(footprint ""
		(layer "B.Cu")
		(at 68.127372 -80.514698 90)
		(property "Reference" "C84"
			(at -32.158686 -14.55039 270)
			(unlocked yes)
			(layer "B.SilkS")
			(effects
				(font
					(size 0.7874 0.5842)
					(thickness 0.1524)
				)
				(justify left mirror)
			)
		)
		(property "Value" ""
			(at 0 0 90)
			(layer "B.Fab")
			(effects
				(font
					(size 1.27 1.27)
				)
				(justify mirror)
			)
		)
		(duplicate_pad_numbers_are_jumpers no)
		(fp_line
			(start 0.7874 -0.4064)
			(end -0.7874 -0.4064)
			(stroke
				(width 0.1524)
				(type default)
			)
			(layer "B.SilkS")
		)
		(fp_line
			(start -0.7874 -0.4064)
			(end -0.7874 0.4064)
			(stroke
				(width 0.1524)
				(type default)
			)
			(layer "B.SilkS")
		)
		(fp_line
			(start 0 0.381)
			(end 0 -0.381)
			(stroke
				(width 0.1524)
				(type default)
			)
			(layer "B.SilkS")
		)
		(fp_line
			(start 0.7874 0.4064)
			(end 0.7874 -0.4064)
			(stroke
				(width 0.1524)
				(type default)
			)
			(layer "B.SilkS")
		)
		(fp_line
			(start -0.7874 0.4064)
			(end 0.7874 0.4064)
			(stroke
				(width 0.1524)
				(type default)
			)
			(layer "B.SilkS")
		)
		(fp_poly
			(pts
				(xy 0.5334 0.254) (xy 0.635 0.254) (xy 0.635 0.2286) (xy 0.635 -0.254) (xy 0.5334 -0.254) (xy 0.5334 -0.2794)
				(xy -0.5334 -0.2794) (xy -0.5334 -0.254) (xy -0.635 -0.254) (xy -0.635 0.254) (xy -0.5334 0.254)
				(xy -0.5334 0.2794) (xy 0.508 0.2794) (xy 0.5334 0.2794)
			)
			(stroke
				(width 0)
				(type default)
			)
			(fill no)
			(layer "B.CrtYd")
		)
		(pad "1" smd rect
			(at -0.40005 0 270)
			(size 0.4572 0.508)
			(layers "B.Cu" "B.Mask" "B.Paste")
			(net "PV_VCCP_NODE1")
		)
		(pad "2" smd rect
			(at 0.40005 0 270)
			(size 0.4572 0.508)
			(layers "B.Cu" "B.Mask" "B.Paste")
			(net "GND")
		)
	)
	(footprint ""
		(layer "B.Cu")
		(at 168.640252 -97.04959 -90)
		(property "Reference" "C380"
			(at -0.90805 -0.443738 270)
			(unlocked yes)
			(layer "B.SilkS")
			(effects
				(font
					(size 0.7874 0.5842)
					(thickness 0.1524)
				)
				(justify left mirror)
			)
		)
		(property "Value" ""
			(at 0 0 90)
			(layer "B.Fab")
			(effects
				(font
					(size 1.27 1.27)
				)
				(justify mirror)
			)
		)
		(duplicate_pad_numbers_are_jumpers no)
		(fp_line
			(start -0.7874 0.4064)
			(end 0.7874 0.4064)
			(stroke
				(width 0.1524)
				(type default)
			)
			(layer "B.SilkS")
		)
		(fp_line
			(start 0.7874 0.4064)
			(end 0.7874 -0.4064)
			(stroke
				(width 0.1524)
				(type default)
			)
			(layer "B.SilkS")
		)
		(fp_line
			(start 0 0.381)
			(end 0 -0.381)
			(stroke
				(width 0.1524)
				(type default)
			)
			(layer "B.SilkS")
		)
		(fp_line
			(start -0.7874 -0.4064)
			(end -0.7874 0.4064)
			(stroke
				(width 0.1524)
				(type default)
			)
			(layer "B.SilkS")
		)
		(fp_line
			(start 0.7874 -0.4064)
			(end -0.7874 -0.4064)
			(stroke
				(width 0.1524)
				(type default)
			)
			(layer "B.SilkS")
		)
		(fp_poly
			(pts
				(xy 0.5334 0.254) (xy 0.635 0.254) (xy 0.635 0.2286) (xy 0.635 -0.254) (xy 0.5334 -0.254) (xy 0.5334 -0.2794)
				(xy -0.5334 -0.2794) (xy -0.5334 -0.254) (xy -0.635 -0.254) (xy -0.635 0.254) (xy -0.5334 0.254)
				(xy -0.5334 0.2794) (xy 0.508 0.2794) (xy 0.5334 0.2794)
			)
			(stroke
				(width 0)
				(type default)
			)
			(fill no)
			(layer "B.CrtYd")
		)
		(pad "1" smd rect
			(at -0.40005 0 90)
			(size 0.4572 0.508)
			(layers "B.Cu" "B.Mask" "B.Paste")
			(net "GND")
		)
		(pad "2" smd rect
			(at 0.40005 0 90)
			(size 0.4572 0.508)
			(layers "B.Cu" "B.Mask" "B.Paste")
			(net "P3V3_NODE1")
		)
	)
	(footprint ""
		(layer "B.Cu")
		(at 69.818758 -138.847322 180)
		(property "Reference" "C248"
			(at 37.946584 -52.737766 0)
			(unlocked yes)
			(layer "B.SilkS")
			(effects
				(font
					(size 0.7874 0.5842)
					(thickness 0.1524)
				)
				(justify mirror)
			)
		)
		(property "Value" ""
			(at 0 0 0)
			(layer "B.Fab")
			(effects
				(font
					(size 1.27 1.27)
				)
				(justify mirror)
			)
		)
		(duplicate_pad_numbers_are_jumpers no)
		(fp_line
			(start 1.2954 0.5842)
			(end 1.2954 -0.5842)
			(stroke
				(width 0.1524)
				(type default)
			)
			(layer "B.SilkS")
		)
		(fp_line
			(start 1.2954 -0.5842)
			(end -1.2954 -0.5842)
			(stroke
				(width 0.1524)
				(type default)
			)
			(layer "B.SilkS")
		)
		(fp_line
			(start 0 -0.5842)
			(end 0 0.5842)
			(stroke
				(width 0.1524)
				(type default)
			)
			(layer "B.SilkS")
		)
		(fp_line
			(start -1.2954 0.5842)
			(end 1.2954 0.5842)
			(stroke
				(width 0.1524)
				(type default)
			)
			(layer "B.SilkS")
		)
		(fp_line
			(start -1.2954 -0.5842)
			(end -1.2954 0.5842)
			(stroke
				(width 0.1524)
				(type default)
			)
			(layer "B.SilkS")
		)
		(fp_poly
			(pts
				(xy -0.8636 -0.4572) (xy -0.8636 -0.3556) (xy -1.143 -0.3556) (xy -1.143 0.3556) (xy -0.8636 0.3556)
				(xy -0.8636 0.4572) (xy 0.8636 0.4572) (xy 0.8636 0.3556) (xy 1.143 0.3556) (xy 1.143 -0.3556) (xy 0.8636 -0.3556)
				(xy 0.8636 -0.4572)
			)
			(stroke
				(width 0)
				(type default)
			)
			(fill no)
			(layer "B.CrtYd")
		)
		(fp_line
			(start 0.884936 0.504952)
			(end 0.884936 -0.504952)
			(stroke
				(width 0.1)
				(type default)
			)
			(layer "B.Fab")
		)
		(fp_line
			(start 0.884936 -0.504952)
			(end -0.884936 -0.504952)
			(stroke
				(width 0.1)
				(type default)
			)
			(layer "B.Fab")
		)
		(fp_line
			(start -0.884936 0.504952)
			(end 0.884936 0.504952)
			(stroke
				(width 0.1)
				(type default)
			)
			(layer "B.Fab")
		)
		(fp_line
			(start -0.884936 -0.504952)
			(end -0.884936 0.504952)
			(stroke
				(width 0.1)
				(type default)
			)
			(layer "B.Fab")
		)
		(pad "1" smd rect
			(at -0.7366 0 270)
			(size 0.7112 0.8128)
			(layers "B.Cu" "B.Mask" "B.Paste")
			(net "P3V3_NODE1")
		)
		(pad "2" smd rect
			(at 0.7366 0 270)
			(size 0.7112 0.8128)
			(layers "B.Cu" "B.Mask" "B.Paste")
			(net "GND")
		)
	)
	(footprint ""
		(layer "B.Cu")
		(at 48.659542 -28.696158 180)
		(property "Reference" "R211"
			(at 1.514602 0.009144 0)
			(unlocked yes)
			(layer "B.SilkS")
			(effects
				(font
					(size 0.7874 0.5842)
					(thickness 0.1524)
				)
				(justify left mirror)
			)
		)
		(property "Value" ""
			(at 0 0 0)
			(layer "B.Fab")
			(effects
				(font
					(size 1.27 1.27)
				)
				(justify mirror)
			)
		)
		(duplicate_pad_numbers_are_jumpers no)
		(fp_line
			(start 0.7874 0.4064)
			(end 0.7874 -0.4064)
			(stroke
				(width 0.1524)
				(type default)
			)
			(layer "B.SilkS")
		)
		(fp_line
			(start 0.7874 -0.4064)
			(end -0.7874 -0.4064)
			(stroke
				(width 0.1524)
				(type default)
			)
			(layer "B.SilkS")
		)
		(fp_line
			(start -0.7874 0.4064)
			(end 0.7874 0.4064)
			(stroke
				(width 0.1524)
				(type default)
			)
			(layer "B.SilkS")
		)
		(fp_line
			(start -0.7874 -0.4064)
			(end -0.7874 0.4064)
			(stroke
				(width 0.1524)
				(type default)
			)
			(layer "B.SilkS")
		)
		(fp_poly
			(pts
				(xy 0.508 0.2794) (xy 0.508 0.2286) (xy 0.635 0.2286) (xy 0.635 -0.254) (xy 0.5334 -0.254) (xy 0.5334 -0.2794)
				(xy -0.5334 -0.2794) (xy -0.5334 -0.254) (xy -0.635 -0.254) (xy -0.635 0.254) (xy -0.5334 0.254)
				(xy -0.5334 0.2794)
			)
			(stroke
				(width 0)
				(type default)
			)
			(fill no)
			(layer "B.CrtYd")
		)
		(pad "1" smd rect
			(at -0.40005 0)
			(size 0.4572 0.508)
			(layers "B.Cu" "B.Mask" "B.Paste")
			(net "GND")
		)
		(pad "2" smd rect
			(at 0.40005 0)
			(size 0.4572 0.508)
			(layers "B.Cu" "B.Mask" "B.Paste")
			(net "PD_NODE1_DM1")
		)
	)
)
